(kicad_pcb
	(version 20260206)
	(generator "pcbnew")
	(generator_version "10.0")
	(general
		(thickness 1.6)
		(legacy_teardrops no)
	)
	(paper "A4")
	(title_block
		(title "01162023_DA0F0TEBIF0_F0T_Expander_BD_F_brd_V02_OCP.brd")
		(comment 1 "Grand Teton / footprints 8078-8087 of 9728")
	)
	(layers
		(0 "F.Cu" signal "TOP")
		(4 "In1.Cu" signal "GND")
		(6 "In2.Cu" signal "VCC")
		(8 "In3.Cu" signal "VCC1")
		(10 "In4.Cu" signal "GND1")
		(12 "In5.Cu" signal "IN1")
		(14 "In6.Cu" signal "GND2")
		(16 "In7.Cu" signal "IN2")
		(18 "In8.Cu" signal "GND3")
		(20 "In9.Cu" signal "IN3")
		(22 "In10.Cu" signal "GND4")
		(24 "In11.Cu" signal "IN4")
		(26 "In12.Cu" signal "GND5")
		(28 "In13.Cu" signal "IN5")
		(30 "In14.Cu" signal "GND6")
		(32 "In15.Cu" signal "IN6")
		(34 "In16.Cu" signal "GND7")
		(2 "B.Cu" signal "BOTTOM")
		(9 "F.Adhes" user "F.Adhesive")
		(11 "B.Adhes" user "B.Adhesive")
		(13 "F.Paste" user "Package Geometry/Pastemask Top")
		(15 "B.Paste" user "Package Geometry/Pastemask Bottom")
		(5 "F.SilkS" user "Ref Des/Silkscreen Top")
		(7 "B.SilkS" user "Ref Des/Silkscreen Bottom")
		(1 "F.Mask" user "Board Geometry/Soldermask Top")
		(3 "B.Mask" user "Board Geometry/Soldermask Bottom")
		(17 "Dwgs.User" user "User.Drawings")
		(19 "Cmts.User" user "User.Comments")
		(21 "Eco1.User" user "User.Eco1")
		(23 "Eco2.User" user "User.Eco2")
		(25 "Edge.Cuts" user "Board Geometry/Outline")
		(27 "Margin" user)
		(31 "F.CrtYd" user "Package Geometry/Place Bound Top")
		(29 "B.CrtYd" user "Package Geometry/Place Bound Bottom")
		(35 "F.Fab" user "Ref Des/Assembly Top")
		(33 "B.Fab" user "Ref Des/Assembly Bottom")
	)
	(footprint ""
		(layer "B.Cu")
		(at 49.1998 -290.674806 180)
		(property "Reference" "C1104"
			(at 0 0 0)
			(layer "B.SilkS")
			(hide yes)
			(effects
				(font
					(size 1.27 1.27)
				)
				(justify mirror)
			)
		)
		(property "Value" ""
			(at 0 0 0)
			(layer "B.Fab")
			(effects
				(font
					(size 1.27 1.27)
				)
				(justify mirror)
			)
		)
		(duplicate_pad_numbers_are_jumpers no)
		(fp_line
			(start 0.299974 0.150114)
			(end 0.299974 -0.150114)
			(stroke
				(width 0.1)
				(type default)
			)
			(layer "B.Fab")
		)
		(fp_line
			(start 0.299974 -0.150114)
			(end -0.299974 -0.150114)
			(stroke
				(width 0.1)
				(type default)
			)
			(layer "B.Fab")
		)
		(fp_line
			(start -0.299974 0.150114)
			(end 0.299974 0.150114)
			(stroke
				(width 0.1)
				(type default)
			)
			(layer "B.Fab")
		)
		(fp_line
			(start -0.299974 -0.150114)
			(end -0.299974 0.150114)
			(stroke
				(width 0.1)
				(type default)
			)
			(layer "B.Fab")
		)
		(pad "1" smd rect
			(at 0.2667 0)
			(size 0.3048 0.381)
			(layers "B.Cu" "B.Mask" "B.Paste")
			(net "P0V8_PEX0")
		)
		(pad "2" smd rect
			(at -0.2667 0)
			(size 0.3048 0.381)
			(layers "B.Cu" "B.Mask" "B.Paste")
			(net "GND")
		)
	)
	(footprint ""
		(layer "B.Cu")
		(at 174.800006 -292.099746 90)
		(property "Reference" "C1416"
			(at 0 0 90)
			(layer "B.SilkS")
			(hide yes)
			(effects
				(font
					(size 1.27 1.27)
				)
				(justify mirror)
			)
		)
		(property "Value" ""
			(at 0 0 90)
			(layer "B.Fab")
			(effects
				(font
					(size 1.27 1.27)
				)
				(justify mirror)
			)
		)
		(duplicate_pad_numbers_are_jumpers no)
		(fp_line
			(start 0.299974 -0.150114)
			(end -0.299974 -0.150114)
			(stroke
				(width 0.1)
				(type default)
			)
			(layer "B.Fab")
		)
		(fp_line
			(start -0.299974 -0.150114)
			(end -0.299974 0.150114)
			(stroke
				(width 0.1)
				(type default)
			)
			(layer "B.Fab")
		)
		(fp_line
			(start 0.299974 0.150114)
			(end 0.299974 -0.150114)
			(stroke
				(width 0.1)
				(type default)
			)
			(layer "B.Fab")
		)
		(fp_line
			(start -0.299974 0.150114)
			(end 0.299974 0.150114)
			(stroke
				(width 0.1)
				(type default)
			)
			(layer "B.Fab")
		)
		(pad "1" smd rect
			(at 0.2667 0 270)
			(size 0.3048 0.381)
			(layers "B.Cu" "B.Mask" "B.Paste")
			(net "P0V8_SERDES_VDDA_PEX1")
		)
		(pad "2" smd rect
			(at -0.2667 0 270)
			(size 0.3048 0.381)
			(layers "B.Cu" "B.Mask" "B.Paste")
			(net "GND")
		)
	)
	(footprint ""
		(layer "B.Cu")
		(at 172.900086 -301.599854 -90)
		(property "Reference" "C1469"
			(at 0 0 90)
			(layer "B.SilkS")
			(hide yes)
			(effects
				(font
					(size 1.27 1.27)
				)
				(justify mirror)
			)
		)
		(property "Value" ""
			(at 0 0 90)
			(layer "B.Fab")
			(effects
				(font
					(size 1.27 1.27)
				)
				(justify mirror)
			)
		)
		(duplicate_pad_numbers_are_jumpers no)
		(fp_line
			(start -0.299974 0.150114)
			(end 0.299974 0.150114)
			(stroke
				(width 0.1)
				(type default)
			)
			(layer "B.Fab")
		)
		(fp_line
			(start 0.299974 0.150114)
			(end 0.299974 -0.150114)
			(stroke
				(width 0.1)
				(type default)
			)
			(layer "B.Fab")
		)
		(fp_line
			(start -0.299974 -0.150114)
			(end -0.299974 0.150114)
			(stroke
				(width 0.1)
				(type default)
			)
			(layer "B.Fab")
		)
		(fp_line
			(start 0.299974 -0.150114)
			(end -0.299974 -0.150114)
			(stroke
				(width 0.1)
				(type default)
			)
			(layer "B.Fab")
		)
		(pad "1" smd rect
			(at 0.2667 0 90)
			(size 0.3048 0.381)
			(layers "B.Cu" "B.Mask" "B.Paste")
			(net "P0V8_SERDES_VDDA_PEX1")
		)
		(pad "2" smd rect
			(at -0.2667 0 90)
			(size 0.3048 0.381)
			(layers "B.Cu" "B.Mask" "B.Paste")
			(net "GND")
		)
	)
	(footprint ""
		(layer "B.Cu")
		(at 403.674834 -286.399732 90)
		(property "Reference" "C3475"
			(at 0 0 90)
			(layer "B.SilkS")
			(hide yes)
			(effects
				(font
					(size 1.27 1.27)
				)
				(justify mirror)
			)
		)
		(property "Value" ""
			(at 0 0 90)
			(layer "B.Fab")
			(effects
				(font
					(size 1.27 1.27)
				)
				(justify mirror)
			)
		)
		(duplicate_pad_numbers_are_jumpers no)
		(fp_line
			(start 0.299974 -0.150114)
			(end -0.299974 -0.150114)
			(stroke
				(width 0.1)
				(type default)
			)
			(layer "B.Fab")
		)
		(fp_line
			(start -0.299974 -0.150114)
			(end -0.299974 0.150114)
			(stroke
				(width 0.1)
				(type default)
			)
			(layer "B.Fab")
		)
		(fp_line
			(start 0.299974 0.150114)
			(end 0.299974 -0.150114)
			(stroke
				(width 0.1)
				(type default)
			)
			(layer "B.Fab")
		)
		(fp_line
			(start -0.299974 0.150114)
			(end 0.299974 0.150114)
			(stroke
				(width 0.1)
				(type default)
			)
			(layer "B.Fab")
		)
		(pad "1" smd rect
			(at 0.2667 0 270)
			(size 0.3048 0.381)
			(layers "B.Cu" "B.Mask" "B.Paste")
			(net "P1V25_SERDES_VDDPLL_PEX3")
		)
		(pad "2" smd rect
			(at -0.2667 0 270)
			(size 0.3048 0.381)
			(layers "B.Cu" "B.Mask" "B.Paste")
			(net "GND")
		)
	)
	(footprint ""
		(layer "B.Cu")
		(at 220.676978 -266.873228)
		(property "Reference" "L101"
			(at 0 0 0)
			(layer "B.SilkS")
			(hide yes)
			(effects
				(font
					(size 1.27 1.27)
				)
				(justify mirror)
			)
		)
		(property "Value" ""
			(at 0 0 0)
			(layer "B.Fab")
			(effects
				(font
					(size 1.27 1.27)
				)
				(justify mirror)
			)
		)
		(duplicate_pad_numbers_are_jumpers no)
		(fp_line
			(start -2.248154 -4.9911)
			(end 2.248154 -4.9911)
			(stroke
				(width 0.1524)
				(type default)
			)
			(layer "B.SilkS")
		)
		(fp_line
			(start -2.248154 -1.689862)
			(end -2.248154 -4.9911)
			(stroke
				(width 0.1524)
				(type default)
			)
			(layer "B.SilkS")
		)
		(fp_line
			(start -2.248154 4.9911)
			(end -2.248154 2.114296)
			(stroke
				(width 0.1524)
				(type default)
			)
			(layer "B.SilkS")
		)
		(fp_line
			(start 2.248154 -4.9911)
			(end 2.248154 -1.689862)
			(stroke
				(width 0.1524)
				(type default)
			)
			(layer "B.SilkS")
		)
		(fp_line
			(start 2.248154 2.114296)
			(end 2.248154 4.9911)
			(stroke
				(width 0.1524)
				(type default)
			)
			(layer "B.SilkS")
		)
		(fp_line
			(start 2.248154 4.9911)
			(end -2.248154 4.9911)
			(stroke
				(width 0.1524)
				(type default)
			)
			(layer "B.SilkS")
		)
		(fp_line
			(start -1.700022 -0.899922)
			(end 1.700022 -0.899922)
			(stroke
				(width 0.1)
				(type default)
			)
			(layer "B.Fab")
		)
		(fp_line
			(start -1.700022 0.899922)
			(end -1.700022 -0.899922)
			(stroke
				(width 0.1)
				(type default)
			)
			(layer "B.Fab")
		)
		(fp_line
			(start 1.700022 -0.899922)
			(end 1.700022 0.899922)
			(stroke
				(width 0.1)
				(type default)
			)
			(layer "B.Fab")
		)
		(fp_line
			(start 1.700022 0.899922)
			(end -1.700022 0.899922)
			(stroke
				(width 0.1)
				(type default)
			)
			(layer "B.Fab")
		)
		(pad "1" smd rect
			(at 1.575054 0 180)
			(size 1.1684 9.8044)
			(layers "B.Cu" "B.Mask" "B.Paste")
			(net "P1V25_PEX1")
		)
		(pad "2" smd rect
			(at -1.575054 0 180)
			(size 1.1684 9.8044)
			(layers "B.Cu" "B.Mask" "B.Paste")
			(net "P1V25_SERDES_VDDPLL_PEX1")
		)
	)
	(footprint ""
		(layer "B.Cu")
		(at 355.520752 -282.259532 180)
		(property "Reference" "PR7173"
			(at 0 0 0)
			(layer "B.SilkS")
			(hide yes)
			(effects
				(font
					(size 1.27 1.27)
				)
				(justify mirror)
			)
		)
		(property "Value" ""
			(at 0 0 0)
			(layer "B.Fab")
			(effects
				(font
					(size 1.27 1.27)
				)
				(justify mirror)
			)
		)
		(duplicate_pad_numbers_are_jumpers no)
		(fp_line
			(start 0.7874 0.4064)
			(end 0.7874 -0.4064)
			(stroke
				(width 0.1524)
				(type default)
			)
			(layer "B.SilkS")
		)
		(fp_line
			(start 0.7874 -0.4064)
			(end -0.7874 -0.4064)
			(stroke
				(width 0.1524)
				(type default)
			)
			(layer "B.SilkS")
		)
		(fp_line
			(start -0.7874 0.4064)
			(end 0.7874 0.4064)
			(stroke
				(width 0.1524)
				(type default)
			)
			(layer "B.SilkS")
		)
		(fp_line
			(start -0.7874 -0.4064)
			(end -0.7874 0.4064)
			(stroke
				(width 0.1524)
				(type default)
			)
			(layer "B.SilkS")
		)
		(fp_line
			(start 0.67945 0.3048)
			(end 0.67945 -0.305054)
			(stroke
				(width 0.1)
				(type default)
			)
			(layer "B.Fab")
		)
		(fp_line
			(start 0.67945 -0.305054)
			(end 0.12065 -0.305054)
			(stroke
				(width 0.1)
				(type default)
			)
			(layer "B.Fab")
		)
		(fp_line
			(start 0.12065 0.3048)
			(end 0.67945 0.3048)
			(stroke
				(width 0.1)
				(type default)
			)
			(layer "B.Fab")
		)
		(fp_line
			(start 0.12065 0.2794)
			(end 0.12065 0.3048)
			(stroke
				(width 0.1)
				(type default)
			)
			(layer "B.Fab")
		)
		(fp_line
			(start 0.12065 -0.2794)
			(end -0.12065 -0.2794)
			(stroke
				(width 0.1)
				(type default)
			)
			(layer "B.Fab")
		)
		(fp_line
			(start 0.12065 -0.305054)
			(end 0.12065 -0.2794)
			(stroke
				(width 0.1)
				(type default)
			)
			(layer "B.Fab")
		)
		(fp_line
			(start -0.120396 0.3048)
			(end -0.120396 0.2794)
			(stroke
				(width 0.1)
				(type default)
			)
			(layer "B.Fab")
		)
		(fp_line
			(start -0.120396 0.2794)
			(end 0.12065 0.2794)
			(stroke
				(width 0.1)
				(type default)
			)
			(layer "B.Fab")
		)
		(fp_line
			(start -0.12065 -0.2794)
			(end -0.12065 -0.3048)
			(stroke
				(width 0.1)
				(type default)
			)
			(layer "B.Fab")
		)
		(fp_line
			(start -0.12065 -0.3048)
			(end -0.67945 -0.3048)
			(stroke
				(width 0.1)
				(type default)
			)
			(layer "B.Fab")
		)
		(fp_line
			(start -0.67945 0.3048)
			(end -0.120396 0.3048)
			(stroke
				(width 0.1)
				(type default)
			)
			(layer "B.Fab")
		)
		(fp_line
			(start -0.67945 -0.3048)
			(end -0.67945 0.3048)
			(stroke
				(width 0.1)
				(type default)
			)
			(layer "B.Fab")
		)
		(pad "1" smd circle
			(at 0.40005 0)
			(size 0 0)
			(layers "B.Cu" "B.Mask" "B.Paste")
			(net "P0V8_PEX2_EN3")
		)
		(pad "2" smd circle
			(at -0.40005 0)
			(size 0 0)
			(layers "B.Cu" "B.Mask" "B.Paste")
			(net "P0V8_PEX3_VCC1")
		)
	)
	(footprint ""
		(layer "B.Cu")
		(at 217.2335 -222.368872)
		(property "Reference" "R6799"
			(at 0 0 0)
			(layer "B.SilkS")
			(hide yes)
			(effects
				(font
					(size 1.27 1.27)
				)
				(justify mirror)
			)
		)
		(property "Value" ""
			(at 0 0 0)
			(layer "B.Fab")
			(effects
				(font
					(size 1.27 1.27)
				)
				(justify mirror)
			)
		)
		(duplicate_pad_numbers_are_jumpers no)
		(fp_line
			(start -0.7874 -0.4064)
			(end -0.7874 0.4064)
			(stroke
				(width 0.1524)
				(type default)
			)
			(layer "B.SilkS")
		)
		(fp_line
			(start -0.7874 0.4064)
			(end 0.7874 0.4064)
			(stroke
				(width 0.1524)
				(type default)
			)
			(layer "B.SilkS")
		)
		(fp_line
			(start 0.7874 -0.4064)
			(end -0.7874 -0.4064)
			(stroke
				(width 0.1524)
				(type default)
			)
			(layer "B.SilkS")
		)
		(fp_line
			(start 0.7874 0.4064)
			(end 0.7874 -0.4064)
			(stroke
				(width 0.1524)
				(type default)
			)
			(layer "B.SilkS")
		)
		(fp_line
			(start -0.67945 -0.3048)
			(end -0.67945 0.3048)
			(stroke
				(width 0.1)
				(type default)
			)
			(layer "B.Fab")
		)
		(fp_line
			(start -0.67945 0.3048)
			(end -0.120396 0.3048)
			(stroke
				(width 0.1)
				(type default)
			)
			(layer "B.Fab")
		)
		(fp_line
			(start -0.12065 -0.3048)
			(end -0.67945 -0.3048)
			(stroke
				(width 0.1)
				(type default)
			)
			(layer "B.Fab")
		)
		(fp_line
			(start -0.12065 -0.2794)
			(end -0.12065 -0.3048)
			(stroke
				(width 0.1)
				(type default)
			)
			(layer "B.Fab")
		)
		(fp_line
			(start -0.120396 0.2794)
			(end 0.12065 0.2794)
			(stroke
				(width 0.1)
				(type default)
			)
			(layer "B.Fab")
		)
		(fp_line
			(start -0.120396 0.3048)
			(end -0.120396 0.2794)
			(stroke
				(width 0.1)
				(type default)
			)
			(layer "B.Fab")
		)
		(fp_line
			(start 0.12065 -0.305054)
			(end 0.12065 -0.2794)
			(stroke
				(width 0.1)
				(type default)
			)
			(layer "B.Fab")
		)
		(fp_line
			(start 0.12065 -0.2794)
			(end -0.12065 -0.2794)
			(stroke
				(width 0.1)
				(type default)
			)
			(layer "B.Fab")
		)
		(fp_line
			(start 0.12065 0.2794)
			(end 0.12065 0.3048)
			(stroke
				(width 0.1)
				(type default)
			)
			(layer "B.Fab")
		)
		(fp_line
			(start 0.12065 0.3048)
			(end 0.67945 0.3048)
			(stroke
				(width 0.1)
				(type default)
			)
			(layer "B.Fab")
		)
		(fp_line
			(start 0.67945 -0.305054)
			(end 0.12065 -0.305054)
			(stroke
				(width 0.1)
				(type default)
			)
			(layer "B.Fab")
		)
		(fp_line
			(start 0.67945 0.3048)
			(end 0.67945 -0.305054)
			(stroke
				(width 0.1)
				(type default)
			)
			(layer "B.Fab")
		)
		(pad "1" smd circle
			(at 0.40005 0 180)
			(size 0 0)
			(layers "B.Cu" "B.Mask" "B.Paste")
			(net "SMB_BIC_FPGA_SCL")
		)
		(pad "2" smd circle
			(at -0.40005 0 180)
			(size 0 0)
			(layers "B.Cu" "B.Mask" "B.Paste")
			(net "SMB_BIC_FPGA_R1_SCL")
		)
	)
	(footprint ""
		(layer "B.Cu")
		(at 304.408078 -300.174914 180)
		(property "Reference" "C3361"
			(at 0 0 0)
			(layer "B.SilkS")
			(hide yes)
			(effects
				(font
					(size 1.27 1.27)
				)
				(justify mirror)
			)
		)
		(property "Value" ""
			(at 0 0 0)
			(layer "B.Fab")
			(effects
				(font
					(size 1.27 1.27)
				)
				(justify mirror)
			)
		)
		(duplicate_pad_numbers_are_jumpers no)
		(fp_line
			(start 0.299974 0.150114)
			(end 0.299974 -0.150114)
			(stroke
				(width 0.1)
				(type default)
			)
			(layer "B.Fab")
		)
		(fp_line
			(start 0.299974 -0.150114)
			(end -0.299974 -0.150114)
			(stroke
				(width 0.1)
				(type default)
			)
			(layer "B.Fab")
		)
		(fp_line
			(start -0.299974 0.150114)
			(end 0.299974 0.150114)
			(stroke
				(width 0.1)
				(type default)
			)
			(layer "B.Fab")
		)
		(fp_line
			(start -0.299974 -0.150114)
			(end -0.299974 0.150114)
			(stroke
				(width 0.1)
				(type default)
			)
			(layer "B.Fab")
		)
		(pad "1" smd rect
			(at 0.2667 0)
			(size 0.3048 0.381)
			(layers "B.Cu" "B.Mask" "B.Paste")
			(net "P1V8_VDDA_PEX2")
		)
		(pad "2" smd rect
			(at -0.2667 0)
			(size 0.3048 0.381)
			(layers "B.Cu" "B.Mask" "B.Paste")
			(net "GND")
		)
	)
	(footprint ""
		(layer "B.Cu")
		(at 338.398612 -89.608152 180)
		(property "Reference" "C2680"
			(at 0 0 0)
			(layer "B.SilkS")
			(hide yes)
			(effects
				(font
					(size 1.27 1.27)
				)
				(justify mirror)
			)
		)
		(property "Value" ""
			(at 0 0 0)
			(layer "B.Fab")
			(effects
				(font
					(size 1.27 1.27)
				)
				(justify mirror)
			)
		)
		(duplicate_pad_numbers_are_jumpers no)
		(fp_line
			(start 0.7874 0.4064)
			(end 0.7874 -0.4064)
			(stroke
				(width 0.1524)
				(type default)
			)
			(layer "B.SilkS")
		)
		(fp_line
			(start 0.7874 -0.4064)
			(end -0.7874 -0.4064)
			(stroke
				(width 0.1524)
				(type default)
			)
			(layer "B.SilkS")
		)
		(fp_line
			(start -0.7874 0.4064)
			(end 0.7874 0.4064)
			(stroke
				(width 0.1524)
				(type default)
			)
			(layer "B.SilkS")
		)
		(fp_line
			(start -0.7874 -0.4064)
			(end -0.7874 0.4064)
			(stroke
				(width 0.1524)
				(type default)
			)
			(layer "B.SilkS")
		)
		(fp_line
			(start 0.67945 0.3048)
			(end 0.67945 -0.305054)
			(stroke
				(width 0.1)
				(type default)
			)
			(layer "B.Fab")
		)
		(fp_line
			(start 0.67945 -0.305054)
			(end 0.12065 -0.305054)
			(stroke
				(width 0.1)
				(type default)
			)
			(layer "B.Fab")
		)
		(fp_line
			(start 0.12065 0.3048)
			(end 0.67945 0.3048)
			(stroke
				(width 0.1)
				(type default)
			)
			(layer "B.Fab")
		)
		(fp_line
			(start 0.12065 0.2794)
			(end 0.12065 0.3048)
			(stroke
				(width 0.1)
				(type default)
			)
			(layer "B.Fab")
		)
		(fp_line
			(start 0.12065 -0.2794)
			(end -0.12065 -0.2794)
			(stroke
				(width 0.1)
				(type default)
			)
			(layer "B.Fab")
		)
		(fp_line
			(start 0.12065 -0.305054)
			(end 0.12065 -0.2794)
			(stroke
				(width 0.1)
				(type default)
			)
			(layer "B.Fab")
		)
		(fp_line
			(start -0.120396 0.3048)
			(end -0.120396 0.2794)
			(stroke
				(width 0.1)
				(type default)
			)
			(layer "B.Fab")
		)
		(fp_line
			(start -0.120396 0.2794)
			(end 0.12065 0.2794)
			(stroke
				(width 0.1)
				(type default)
			)
			(layer "B.Fab")
		)
		(fp_line
			(start -0.12065 -0.2794)
			(end -0.12065 -0.3048)
			(stroke
				(width 0.1)
				(type default)
			)
			(layer "B.Fab")
		)
		(fp_line
			(start -0.12065 -0.3048)
			(end -0.67945 -0.3048)
			(stroke
				(width 0.1)
				(type default)
			)
			(layer "B.Fab")
		)
		(fp_line
			(start -0.67945 0.3048)
			(end -0.120396 0.3048)
			(stroke
				(width 0.1)
				(type default)
			)
			(layer "B.Fab")
		)
		(fp_line
			(start -0.67945 -0.3048)
			(end -0.67945 0.3048)
			(stroke
				(width 0.1)
				(type default)
			)
			(layer "B.Fab")
		)
		(pad "1" smd circle
			(at 0.40005 0)
			(size 0 0)
			(layers "B.Cu" "B.Mask" "B.Paste")
			(net "P3V3_VDD_9ZXL0851_8_15")
		)
		(pad "2" smd circle
			(at -0.40005 0)
			(size 0 0)
			(layers "B.Cu" "B.Mask" "B.Paste")
			(net "GND")
		)
	)
	(footprint ""
		(layer "B.Cu")
		(at 183.82488 -305.399948 -90)
		(property "Reference" "C3160"
			(at 0 0 90)
			(layer "B.SilkS")
			(hide yes)
			(effects
				(font
					(size 1.27 1.27)
				)
				(justify mirror)
			)
		)
		(property "Value" ""
			(at 0 0 90)
			(layer "B.Fab")
			(effects
				(font
					(size 1.27 1.27)
				)
				(justify mirror)
			)
		)
		(duplicate_pad_numbers_are_jumpers no)
		(fp_line
			(start -0.299974 0.150114)
			(end 0.299974 0.150114)
			(stroke
				(width 0.1)
				(type default)
			)
			(layer "B.Fab")
		)
		(fp_line
			(start 0.299974 0.150114)
			(end 0.299974 -0.150114)
			(stroke
				(width 0.1)
				(type default)
			)
			(layer "B.Fab")
		)
		(fp_line
			(start -0.299974 -0.150114)
			(end -0.299974 0.150114)
			(stroke
				(width 0.1)
				(type default)
			)
			(layer "B.Fab")
		)
		(fp_line
			(start 0.299974 -0.150114)
			(end -0.299974 -0.150114)
			(stroke
				(width 0.1)
				(type default)
			)
			(layer "B.Fab")
		)
		(pad "1" smd rect
			(at 0.2667 0 90)
			(size 0.3048 0.381)
			(layers "B.Cu" "B.Mask" "B.Paste")
			(net "P1V25_SERDES_VDDPLL_PEX1")
		)
		(pad "2" smd rect
			(at -0.2667 0 90)
			(size 0.3048 0.381)
			(layers "B.Cu" "B.Mask" "B.Paste")
			(net "GND")
		)
	)
)
